(kicad_pcb
	(version 20260206)
	(generator "pcbnew")
	(generator_version "10.0")
	(general
		(thickness 1.6)
		(legacy_teardrops no)
	)
	(paper "A4")
	(title_block
		(title "03242023_DA0F0TMBIJ0_F0T_Motherboard_J_brd_V01_OCP.brd")
		(comment 1 "Grand Teton / footprint 3833 of 6105 (J14), pads 225-291 of 291")
	)
	(layers
		(0 "F.Cu" signal "TOP")
		(4 "In1.Cu" signal "GND")
		(6 "In2.Cu" signal "IN1")
		(8 "In3.Cu" signal "GND1")
		(10 "In4.Cu" signal "IN2")
		(12 "In5.Cu" signal "GND2")
		(14 "In6.Cu" signal "IN3")
		(16 "In7.Cu" signal "GND3")
		(18 "In8.Cu" signal "VCC")
		(20 "In9.Cu" signal "VCC1")
		(22 "In10.Cu" signal "GND4")
		(24 "In11.Cu" signal "IN4")
		(26 "In12.Cu" signal "GND5")
		(28 "In13.Cu" signal "IN5")
		(30 "In14.Cu" signal "GND6")
		(32 "In15.Cu" signal "IN6")
		(34 "In16.Cu" signal "GND7")
		(2 "B.Cu" signal "BOTTOM")
		(9 "F.Adhes" user "F.Adhesive")
		(11 "B.Adhes" user "B.Adhesive")
		(13 "F.Paste" user "Package Geometry/Pastemask Top")
		(15 "B.Paste" user "Package Geometry/Pastemask Bottom")
		(5 "F.SilkS" user "Ref Des/Silkscreen Top")
		(7 "B.SilkS" user "Ref Des/Silkscreen Bottom")
		(1 "F.Mask" user "Board Geometry/Soldermask Top")
		(3 "B.Mask" user "Board Geometry/Soldermask Bottom")
		(17 "Dwgs.User" user "User.Drawings")
		(19 "Cmts.User" user "User.Comments")
		(21 "Eco1.User" user "User.Eco1")
		(23 "Eco2.User" user "User.Eco2")
		(25 "Edge.Cuts" user "Board Geometry/Outline")
		(27 "Margin" user)
		(31 "F.CrtYd" user "Package Geometry/Place Bound Top")
		(29 "B.CrtYd" user "Package Geometry/Place Bound Bottom")
		(35 "F.Fab" user "Ref Des/Assembly Top")
		(33 "B.Fab" user "Ref Des/Assembly Bottom")
	)
	(footprint ""
		(layer "F.Cu")
		(at 438.978548 -258.091686)
		(property "Reference" "J14"
			(at -3.683 -81.702148 0)
			(unlocked yes)
			(layer "F.SilkS")
			(effects
				(font
					(size 0.7874 0.5842)
					(thickness 0.1524)
				)
				(justify left)
			)
		)
		(property "Value" ""
			(at 0 0 0)
			(layer "F.Fab")
			(effects
				(font
					(size 1.27 1.27)
				)
			)
		)
		(duplicate_pad_numbers_are_jumpers no)
		(pad "225" smd rect
			(at 2.050034 9.774936 270)
			(size 0.519938 1.4986)
			(layers "F.Cu" "F.Mask" "F.Paste")
			(net "M_G_CPU0_SB_CA<5>")
		)
		(pad "226" smd rect
			(at 2.050034 10.625074 270)
			(size 0.519938 1.4986)
			(layers "F.Cu" "F.Mask" "F.Paste")
			(net "GND")
		)
		(pad "227" smd rect
			(at 2.050034 11.474958 270)
			(size 0.519938 1.4986)
			(layers "F.Cu" "F.Mask" "F.Paste")
			(net "M_G_CPU0_SB_PAR")
		)
		(pad "228" smd rect
			(at 2.050034 12.325096 270)
			(size 0.519938 1.4986)
			(layers "F.Cu" "F.Mask" "F.Paste")
			(net "GND")
		)
		(pad "229" smd rect
			(at 2.050034 13.17498 270)
			(size 0.519938 1.4986)
			(layers "F.Cu" "F.Mask" "F.Paste")
			(net "M_G_CPU0_SB_CS_N<3>")
		)
		(pad "230" smd rect
			(at 2.050034 14.025118 270)
			(size 0.519938 1.4986)
			(layers "F.Cu" "F.Mask" "F.Paste")
			(net "GND")
		)
		(pad "231" smd rect
			(at 2.050034 14.875002 270)
			(size 0.519938 1.4986)
			(layers "F.Cu" "F.Mask" "F.Paste")
			(net "TP_CHG_CPU0_DIMM2_FRU_5")
		)
		(pad "232" smd rect
			(at 2.050034 15.724886 270)
			(size 0.519938 1.4986)
			(layers "F.Cu" "F.Mask" "F.Paste")
			(net "TP_CHG_CPU0_DIMM2_FRU_6")
		)
		(pad "233" smd rect
			(at 2.050034 16.575024 270)
			(size 0.519938 1.4986)
			(layers "F.Cu" "F.Mask" "F.Paste")
			(net "GND")
		)
		(pad "234" smd rect
			(at 2.050034 17.424908 270)
			(size 0.519938 1.4986)
			(layers "F.Cu" "F.Mask" "F.Paste")
			(net "M_G_CPU0_SB_CB<6>")
		)
		(pad "235" smd rect
			(at 2.050034 18.275046 270)
			(size 0.519938 1.4986)
			(layers "F.Cu" "F.Mask" "F.Paste")
			(net "GND")
		)
		(pad "236" smd rect
			(at 2.050034 19.12493 270)
			(size 0.519938 1.4986)
			(layers "F.Cu" "F.Mask" "F.Paste")
			(net "M_G_CPU0_SB_CB<7>")
		)
		(pad "237" smd rect
			(at 2.050034 19.975068 270)
			(size 0.519938 1.4986)
			(layers "F.Cu" "F.Mask" "F.Paste")
			(net "GND")
		)
		(pad "238" smd rect
			(at 2.050034 20.824952 270)
			(size 0.519938 1.4986)
			(layers "F.Cu" "F.Mask" "F.Paste")
			(net "M_G_CPU0_SB_DQS_DN<4>")
		)
		(pad "239" smd rect
			(at 2.050034 21.67509 270)
			(size 0.519938 1.4986)
			(layers "F.Cu" "F.Mask" "F.Paste")
			(net "M_G_CPU0_SB_DQS_DP<4>")
		)
		(pad "240" smd rect
			(at 2.050034 22.524974 270)
			(size 0.519938 1.4986)
			(layers "F.Cu" "F.Mask" "F.Paste")
			(net "GND")
		)
		(pad "241" smd rect
			(at 2.050034 23.375112 270)
			(size 0.519938 1.4986)
			(layers "F.Cu" "F.Mask" "F.Paste")
			(net "M_G_CPU0_SB_CB<2>")
		)
		(pad "242" smd rect
			(at 2.050034 24.224996 270)
			(size 0.519938 1.4986)
			(layers "F.Cu" "F.Mask" "F.Paste")
			(net "GND")
		)
		(pad "243" smd rect
			(at 2.050034 25.07488 270)
			(size 0.519938 1.4986)
			(layers "F.Cu" "F.Mask" "F.Paste")
			(net "M_G_CPU0_SB_CB<3>")
		)
		(pad "244" smd rect
			(at 2.050034 25.925018 270)
			(size 0.519938 1.4986)
			(layers "F.Cu" "F.Mask" "F.Paste")
			(net "GND")
		)
		(pad "245" smd rect
			(at 2.050034 26.774902 270)
			(size 0.519938 1.4986)
			(layers "F.Cu" "F.Mask" "F.Paste")
			(net "M_G_CPU0_SB_DQ<2>")
		)
		(pad "246" smd rect
			(at 2.050034 27.62504 270)
			(size 0.519938 1.4986)
			(layers "F.Cu" "F.Mask" "F.Paste")
			(net "GND")
		)
		(pad "247" smd rect
			(at 2.050034 28.474924 270)
			(size 0.519938 1.4986)
			(layers "F.Cu" "F.Mask" "F.Paste")
			(net "M_G_CPU0_SB_DQ<3>")
		)
		(pad "248" smd rect
			(at 2.050034 29.325062 270)
			(size 0.519938 1.4986)
			(layers "F.Cu" "F.Mask" "F.Paste")
			(net "GND")
		)
		(pad "249" smd rect
			(at 2.050034 30.174946 270)
			(size 0.519938 1.4986)
			(layers "F.Cu" "F.Mask" "F.Paste")
			(net "M_G_CPU0_SB_DQS_DN<5>")
		)
		(pad "250" smd rect
			(at 2.050034 31.025084 270)
			(size 0.519938 1.4986)
			(layers "F.Cu" "F.Mask" "F.Paste")
			(net "M_G_CPU0_SB_DQS_DP<5>")
		)
		(pad "251" smd rect
			(at 2.050034 31.874968 270)
			(size 0.519938 1.4986)
			(layers "F.Cu" "F.Mask" "F.Paste")
			(net "GND")
		)
		(pad "252" smd rect
			(at 2.050034 32.725106 270)
			(size 0.519938 1.4986)
			(layers "F.Cu" "F.Mask" "F.Paste")
			(net "M_G_CPU0_SB_DQ<6>")
		)
		(pad "253" smd rect
			(at 2.050034 33.57499 270)
			(size 0.519938 1.4986)
			(layers "F.Cu" "F.Mask" "F.Paste")
			(net "GND")
		)
		(pad "254" smd rect
			(at 2.050034 34.425128 270)
			(size 0.519938 1.4986)
			(layers "F.Cu" "F.Mask" "F.Paste")
			(net "M_G_CPU0_SB_DQ<7>")
		)
		(pad "255" smd rect
			(at 2.050034 35.275012 270)
			(size 0.519938 1.4986)
			(layers "F.Cu" "F.Mask" "F.Paste")
			(net "GND")
		)
		(pad "256" smd rect
			(at 2.050034 36.124896 270)
			(size 0.519938 1.4986)
			(layers "F.Cu" "F.Mask" "F.Paste")
			(net "M_G_CPU0_SB_DQ<10>")
		)
		(pad "257" smd rect
			(at 2.050034 36.975034 270)
			(size 0.519938 1.4986)
			(layers "F.Cu" "F.Mask" "F.Paste")
			(net "GND")
		)
		(pad "258" smd rect
			(at 2.050034 37.824918 270)
			(size 0.519938 1.4986)
			(layers "F.Cu" "F.Mask" "F.Paste")
			(net "M_G_CPU0_SB_DQ<11>")
		)
		(pad "259" smd rect
			(at 2.050034 38.675056 270)
			(size 0.519938 1.4986)
			(layers "F.Cu" "F.Mask" "F.Paste")
			(net "GND")
		)
		(pad "260" smd rect
			(at 2.050034 39.52494 270)
			(size 0.519938 1.4986)
			(layers "F.Cu" "F.Mask" "F.Paste")
			(net "M_G_CPU0_SB_DQS_DN<6>")
		)
		(pad "261" smd rect
			(at 2.050034 40.375078 270)
			(size 0.519938 1.4986)
			(layers "F.Cu" "F.Mask" "F.Paste")
			(net "M_G_CPU0_SB_DQS_DP<6>")
		)
		(pad "262" smd rect
			(at 2.050034 41.224962 270)
			(size 0.519938 1.4986)
			(layers "F.Cu" "F.Mask" "F.Paste")
			(net "GND")
		)
		(pad "263" smd rect
			(at 2.050034 42.0751 270)
			(size 0.519938 1.4986)
			(layers "F.Cu" "F.Mask" "F.Paste")
			(net "M_G_CPU0_SB_DQ<14>")
		)
		(pad "264" smd rect
			(at 2.050034 42.924984 270)
			(size 0.519938 1.4986)
			(layers "F.Cu" "F.Mask" "F.Paste")
			(net "GND")
		)
		(pad "265" smd rect
			(at 2.050034 43.775122 270)
			(size 0.519938 1.4986)
			(layers "F.Cu" "F.Mask" "F.Paste")
			(net "M_G_CPU0_SB_DQ<15>")
		)
		(pad "266" smd rect
			(at 2.050034 44.625006 270)
			(size 0.519938 1.4986)
			(layers "F.Cu" "F.Mask" "F.Paste")
			(net "GND")
		)
		(pad "267" smd rect
			(at 2.050034 45.47489 270)
			(size 0.519938 1.4986)
			(layers "F.Cu" "F.Mask" "F.Paste")
			(net "M_G_CPU0_SB_DQ<18>")
		)
		(pad "268" smd rect
			(at 2.050034 46.325028 270)
			(size 0.519938 1.4986)
			(layers "F.Cu" "F.Mask" "F.Paste")
			(net "GND")
		)
		(pad "269" smd rect
			(at 2.050034 47.174912 270)
			(size 0.519938 1.4986)
			(layers "F.Cu" "F.Mask" "F.Paste")
			(net "M_G_CPU0_SB_DQ<19>")
		)
		(pad "270" smd rect
			(at 2.050034 48.02505 270)
			(size 0.519938 1.4986)
			(layers "F.Cu" "F.Mask" "F.Paste")
			(net "GND")
		)
		(pad "271" smd rect
			(at 2.050034 48.874934 270)
			(size 0.519938 1.4986)
			(layers "F.Cu" "F.Mask" "F.Paste")
			(net "M_G_CPU0_SB_DQS_DN<7>")
		)
		(pad "272" smd rect
			(at 2.050034 49.725072 270)
			(size 0.519938 1.4986)
			(layers "F.Cu" "F.Mask" "F.Paste")
			(net "M_G_CPU0_SB_DQS_DP<7>")
		)
		(pad "273" smd rect
			(at 2.050034 50.574956 270)
			(size 0.519938 1.4986)
			(layers "F.Cu" "F.Mask" "F.Paste")
			(net "GND")
		)
		(pad "274" smd rect
			(at 2.050034 51.425094 270)
			(size 0.519938 1.4986)
			(layers "F.Cu" "F.Mask" "F.Paste")
			(net "M_G_CPU0_SB_DQ<22>")
		)
		(pad "275" smd rect
			(at 2.050034 52.274978 270)
			(size 0.519938 1.4986)
			(layers "F.Cu" "F.Mask" "F.Paste")
			(net "GND")
		)
		(pad "276" smd rect
			(at 2.050034 53.125116 270)
			(size 0.519938 1.4986)
			(layers "F.Cu" "F.Mask" "F.Paste")
			(net "M_G_CPU0_SB_DQ<23>")
		)
		(pad "277" smd rect
			(at 2.050034 53.975 270)
			(size 0.519938 1.4986)
			(layers "F.Cu" "F.Mask" "F.Paste")
			(net "GND")
		)
		(pad "278" smd rect
			(at 2.050034 54.824884 270)
			(size 0.519938 1.4986)
			(layers "F.Cu" "F.Mask" "F.Paste")
			(net "M_G_CPU0_SB_DQ<26>")
		)
		(pad "279" smd rect
			(at 2.050034 55.675022 270)
			(size 0.519938 1.4986)
			(layers "F.Cu" "F.Mask" "F.Paste")
			(net "GND")
		)
		(pad "280" smd rect
			(at 2.050034 56.524906 270)
			(size 0.519938 1.4986)
			(layers "F.Cu" "F.Mask" "F.Paste")
			(net "M_G_CPU0_SB_DQ<27>")
		)
		(pad "281" smd rect
			(at 2.050034 57.375044 270)
			(size 0.519938 1.4986)
			(layers "F.Cu" "F.Mask" "F.Paste")
			(net "GND")
		)
		(pad "282" smd rect
			(at 2.050034 58.224928 270)
			(size 0.519938 1.4986)
			(layers "F.Cu" "F.Mask" "F.Paste")
			(net "M_G_CPU0_SB_DQS_DN<8>")
		)
		(pad "283" smd rect
			(at 2.050034 59.075066 270)
			(size 0.519938 1.4986)
			(layers "F.Cu" "F.Mask" "F.Paste")
			(net "M_G_CPU0_SB_DQS_DP<8>")
		)
		(pad "284" smd rect
			(at 2.050034 59.92495 270)
			(size 0.519938 1.4986)
			(layers "F.Cu" "F.Mask" "F.Paste")
			(net "GND")
		)
		(pad "285" smd rect
			(at 2.050034 60.775088 270)
			(size 0.519938 1.4986)
			(layers "F.Cu" "F.Mask" "F.Paste")
			(net "M_G_CPU0_SB_DQ<30>")
		)
		(pad "286" smd rect
			(at 2.050034 61.624972 270)
			(size 0.519938 1.4986)
			(layers "F.Cu" "F.Mask" "F.Paste")
			(net "GND")
		)
		(pad "287" smd rect
			(at 2.050034 62.47511 270)
			(size 0.519938 1.4986)
			(layers "F.Cu" "F.Mask" "F.Paste")
			(net "M_G_CPU0_SB_DQ<31>")
		)
		(pad "288" smd rect
			(at 2.050034 63.324994 270)
			(size 0.519938 1.4986)
			(layers "F.Cu" "F.Mask" "F.Paste")
			(net "GND")
		)
		(pad "G1" thru_hole oval
			(at 0 -68.97497)
			(size 2.8194 1.5748)
			(drill oval 2.4384 1.1938)
			(layers "*.Cu" "*.Mask")
			(remove_unused_layers no)
			(net "GND")
			(clearance 0.127)
			(thermal_gap 0.127)
		)
		(pad "G2" thru_hole oval
			(at 0 3.875024)
			(size 2.8194 1.5748)
			(drill oval 2.4384 1.1938)
			(layers "*.Cu" "*.Mask")
			(remove_unused_layers no)
			(net "GND")
			(clearance 0.127)
			(thermal_gap 0.127)
		)
		(pad "G3" thru_hole oval
			(at 0 68.97497)
			(size 2.8194 1.5748)
			(drill oval 2.4384 1.1938)
			(layers "*.Cu" "*.Mask")
			(remove_unused_layers no)
			(net "GND")
			(clearance 0.127)
			(thermal_gap 0.127)
		)
	)
)
